(kicad_pcb
	(version 20260206)
	(generator "pcbnew")
	(generator_version "10.0")
	(general
		(thickness 1.6)
		(legacy_teardrops no)
	)
	(paper "A4")
	(title_block
		(title "04192023_DAF0TMB3IC0_F0TG_MB_C_brd_V02_OCP.brd")
		(comment 1 "Grand Teton / footprints 3487-3492 of 8354")
	)
	(layers
		(0 "F.Cu" signal "TOP")
		(4 "In1.Cu" signal "GND")
		(6 "In2.Cu" signal "IN1")
		(8 "In3.Cu" signal "GND1")
		(10 "In4.Cu" signal "IN2")
		(12 "In5.Cu" signal "GND2")
		(14 "In6.Cu" signal "IN3")
		(16 "In7.Cu" signal "GND3")
		(18 "In8.Cu" signal "VCC")
		(20 "In9.Cu" signal "VCC1")
		(22 "In10.Cu" signal "GND4")
		(24 "In11.Cu" signal "IN4")
		(26 "In12.Cu" signal "GND5")
		(28 "In13.Cu" signal "IN5")
		(30 "In14.Cu" signal "GND6")
		(32 "In15.Cu" signal "IN6")
		(34 "In16.Cu" signal "GND7")
		(2 "B.Cu" signal "BOTTOM")
		(9 "F.Adhes" user "F.Adhesive")
		(11 "B.Adhes" user "B.Adhesive")
		(13 "F.Paste" user "Package Geometry/Pastemask Top")
		(15 "B.Paste" user "Package Geometry/Pastemask Bottom")
		(5 "F.SilkS" user "Ref Des/Silkscreen Top")
		(7 "B.SilkS" user "Ref Des/Silkscreen Bottom")
		(1 "F.Mask" user "Board Geometry/Soldermask Top")
		(3 "B.Mask" user "Board Geometry/Soldermask Bottom")
		(17 "Dwgs.User" user "User.Drawings")
		(19 "Cmts.User" user "User.Comments")
		(21 "Eco1.User" user "User.Eco1")
		(23 "Eco2.User" user "User.Eco2")
		(25 "Edge.Cuts" user "Board Geometry/Outline")
		(27 "Margin" user)
		(31 "F.CrtYd" user "Package Geometry/Place Bound Top")
		(29 "B.CrtYd" user "Package Geometry/Place Bound Bottom")
		(35 "F.Fab" user "Ref Des/Assembly Top")
		(33 "B.Fab" user "Ref Des/Assembly Bottom")
	)
	(footprint ""
		(layer "F.Cu")
		(at 351.407222 -424.279314 180)
		(property "Reference" "R4559"
			(at 0 0 180)
			(layer "F.SilkS")
			(hide yes)
			(effects
				(font
					(size 1.27 1.27)
				)
			)
		)
		(property "Value" ""
			(at 0 0 180)
			(layer "F.Fab")
			(effects
				(font
					(size 1.27 1.27)
				)
			)
		)
		(duplicate_pad_numbers_are_jumpers no)
		(fp_line
			(start 0.7874 0.4064)
			(end -0.7874 0.4064)
			(stroke
				(width 0.1524)
				(type default)
			)
			(layer "F.SilkS")
		)
		(fp_line
			(start 0.7874 -0.4064)
			(end 0.7874 0.4064)
			(stroke
				(width 0.1524)
				(type default)
			)
			(layer "F.SilkS")
		)
		(fp_line
			(start -0.7874 0.4064)
			(end -0.7874 -0.4064)
			(stroke
				(width 0.1524)
				(type default)
			)
			(layer "F.SilkS")
		)
		(fp_line
			(start -0.7874 -0.4064)
			(end 0.7874 -0.4064)
			(stroke
				(width 0.1524)
				(type default)
			)
			(layer "F.SilkS")
		)
		(fp_line
			(start 0.67945 0.3048)
			(end 0.120396 0.3048)
			(stroke
				(width 0.1)
				(type default)
			)
			(layer "F.Fab")
		)
		(fp_line
			(start 0.67945 -0.3048)
			(end 0.67945 0.3048)
			(stroke
				(width 0.1)
				(type default)
			)
			(layer "F.Fab")
		)
		(fp_line
			(start 0.12065 -0.2794)
			(end 0.12065 -0.3048)
			(stroke
				(width 0.1)
				(type default)
			)
			(layer "F.Fab")
		)
		(fp_line
			(start 0.12065 -0.3048)
			(end 0.67945 -0.3048)
			(stroke
				(width 0.1)
				(type default)
			)
			(layer "F.Fab")
		)
		(fp_line
			(start 0.120396 0.3048)
			(end 0.120396 0.2794)
			(stroke
				(width 0.1)
				(type default)
			)
			(layer "F.Fab")
		)
		(fp_line
			(start 0.120396 0.2794)
			(end -0.12065 0.2794)
			(stroke
				(width 0.1)
				(type default)
			)
			(layer "F.Fab")
		)
		(fp_line
			(start -0.12065 0.3048)
			(end -0.67945 0.3048)
			(stroke
				(width 0.1)
				(type default)
			)
			(layer "F.Fab")
		)
		(fp_line
			(start -0.12065 0.2794)
			(end -0.12065 0.3048)
			(stroke
				(width 0.1)
				(type default)
			)
			(layer "F.Fab")
		)
		(fp_line
			(start -0.12065 -0.2794)
			(end 0.12065 -0.2794)
			(stroke
				(width 0.1)
				(type default)
			)
			(layer "F.Fab")
		)
		(fp_line
			(start -0.12065 -0.305054)
			(end -0.12065 -0.2794)
			(stroke
				(width 0.1)
				(type default)
			)
			(layer "F.Fab")
		)
		(fp_line
			(start -0.67945 0.3048)
			(end -0.67945 -0.305054)
			(stroke
				(width 0.1)
				(type default)
			)
			(layer "F.Fab")
		)
		(fp_line
			(start -0.67945 -0.305054)
			(end -0.12065 -0.305054)
			(stroke
				(width 0.1)
				(type default)
			)
			(layer "F.Fab")
		)
		(pad "1" smd circle
			(at -0.40005 0 180)
			(size 0 0)
			(layers "F.Cu" "F.Mask" "F.Paste")
			(net "SWB_HSC_PWRGD")
		)
		(pad "2" smd circle
			(at 0.40005 0 180)
			(size 0 0)
			(layers "F.Cu" "F.Mask" "F.Paste")
			(net "GND")
		)
	)
	(footprint ""
		(layer "F.Cu")
		(at 192.913 -100.294948 90)
		(property "Reference" "R222"
			(at 0 0 90)
			(layer "F.SilkS")
			(hide yes)
			(effects
				(font
					(size 1.27 1.27)
				)
			)
		)
		(property "Value" ""
			(at 0 0 90)
			(layer "F.Fab")
			(effects
				(font
					(size 1.27 1.27)
				)
			)
		)
		(duplicate_pad_numbers_are_jumpers no)
		(fp_line
			(start 0.7874 -0.4064)
			(end 0.7874 0.4064)
			(stroke
				(width 0.1524)
				(type default)
			)
			(layer "F.SilkS")
		)
		(fp_line
			(start -0.7874 -0.4064)
			(end 0.7874 -0.4064)
			(stroke
				(width 0.1524)
				(type default)
			)
			(layer "F.SilkS")
		)
		(fp_line
			(start 0.7874 0.4064)
			(end -0.7874 0.4064)
			(stroke
				(width 0.1524)
				(type default)
			)
			(layer "F.SilkS")
		)
		(fp_line
			(start -0.7874 0.4064)
			(end -0.7874 -0.4064)
			(stroke
				(width 0.1524)
				(type default)
			)
			(layer "F.SilkS")
		)
		(fp_line
			(start -0.12065 -0.305054)
			(end -0.12065 -0.2794)
			(stroke
				(width 0.1)
				(type default)
			)
			(layer "F.Fab")
		)
		(fp_line
			(start -0.67945 -0.305054)
			(end -0.12065 -0.305054)
			(stroke
				(width 0.1)
				(type default)
			)
			(layer "F.Fab")
		)
		(fp_line
			(start 0.67945 -0.3048)
			(end 0.67945 0.3048)
			(stroke
				(width 0.1)
				(type default)
			)
			(layer "F.Fab")
		)
		(fp_line
			(start 0.12065 -0.3048)
			(end 0.67945 -0.3048)
			(stroke
				(width 0.1)
				(type default)
			)
			(layer "F.Fab")
		)
		(fp_line
			(start 0.12065 -0.2794)
			(end 0.12065 -0.3048)
			(stroke
				(width 0.1)
				(type default)
			)
			(layer "F.Fab")
		)
		(fp_line
			(start -0.12065 -0.2794)
			(end 0.12065 -0.2794)
			(stroke
				(width 0.1)
				(type default)
			)
			(layer "F.Fab")
		)
		(fp_line
			(start 0.120396 0.2794)
			(end -0.12065 0.2794)
			(stroke
				(width 0.1)
				(type default)
			)
			(layer "F.Fab")
		)
		(fp_line
			(start -0.12065 0.2794)
			(end -0.12065 0.3048)
			(stroke
				(width 0.1)
				(type default)
			)
			(layer "F.Fab")
		)
		(fp_line
			(start 0.67945 0.3048)
			(end 0.120396 0.3048)
			(stroke
				(width 0.1)
				(type default)
			)
			(layer "F.Fab")
		)
		(fp_line
			(start 0.120396 0.3048)
			(end 0.120396 0.2794)
			(stroke
				(width 0.1)
				(type default)
			)
			(layer "F.Fab")
		)
		(fp_line
			(start -0.12065 0.3048)
			(end -0.67945 0.3048)
			(stroke
				(width 0.1)
				(type default)
			)
			(layer "F.Fab")
		)
		(fp_line
			(start -0.67945 0.3048)
			(end -0.67945 -0.305054)
			(stroke
				(width 0.1)
				(type default)
			)
			(layer "F.Fab")
		)
		(pad "1" smd circle
			(at -0.40005 0 90)
			(size 0 0)
			(layers "F.Cu" "F.Mask" "F.Paste")
			(net "CPU0_SP5R3")
		)
		(pad "2" smd circle
			(at 0.40005 0 90)
			(size 0 0)
			(layers "F.Cu" "F.Mask" "F.Paste")
			(net "FM_CPU0_SP5R3")
		)
	)
	(footprint ""
		(layer "F.Cu")
		(at 363.72292 -400.903694)
		(property "Reference" "L23"
			(at -2.3876 -2.969768 0)
			(unlocked yes)
			(layer "F.SilkS")
			(effects
				(font
					(size 0.7874 0.5842)
					(thickness 0.1524)
				)
				(justify left)
			)
		)
		(property "Value" ""
			(at 0 0 0)
			(layer "F.Fab")
			(effects
				(font
					(size 1.27 1.27)
				)
			)
		)
		(duplicate_pad_numbers_are_jumpers no)
		(fp_line
			(start -2.249932 -2.249932)
			(end 2.249932 -2.249932)
			(stroke
				(width 0.1524)
				(type default)
			)
			(layer "F.SilkS")
		)
		(fp_line
			(start -2.249932 -1.3843)
			(end -2.249932 -2.249932)
			(stroke
				(width 0.1524)
				(type default)
			)
			(layer "F.SilkS")
		)
		(fp_line
			(start -2.249932 2.249932)
			(end -2.249932 1.3843)
			(stroke
				(width 0.1524)
				(type default)
			)
			(layer "F.SilkS")
		)
		(fp_line
			(start 2.249932 -2.249932)
			(end 2.249932 -1.3843)
			(stroke
				(width 0.1524)
				(type default)
			)
			(layer "F.SilkS")
		)
		(fp_line
			(start 2.249932 1.3843)
			(end 2.249932 2.249932)
			(stroke
				(width 0.1524)
				(type default)
			)
			(layer "F.SilkS")
		)
		(fp_line
			(start 2.249932 2.249932)
			(end -2.249932 2.249932)
			(stroke
				(width 0.1524)
				(type default)
			)
			(layer "F.SilkS")
		)
		(fp_line
			(start -2.249932 -2.249932)
			(end 2.249932 -2.249932)
			(stroke
				(width 0.1)
				(type default)
			)
			(layer "F.Fab")
		)
		(fp_line
			(start -2.249932 2.249932)
			(end -2.249932 -2.249932)
			(stroke
				(width 0.1)
				(type default)
			)
			(layer "F.Fab")
		)
		(fp_line
			(start 2.249932 -2.249932)
			(end 2.249932 2.249932)
			(stroke
				(width 0.1)
				(type default)
			)
			(layer "F.Fab")
		)
		(fp_line
			(start 2.249932 2.249932)
			(end -2.249932 2.249932)
			(stroke
				(width 0.1)
				(type default)
			)
			(layer "F.Fab")
		)
		(pad "1" smd rect
			(at -1.82499 0)
			(size 1.0668 2.5146)
			(layers "F.Cu" "F.Mask" "F.Paste")
			(net "P0V9_CPU0_RT_2D")
		)
		(pad "2" smd rect
			(at 1.82499 0)
			(size 1.0668 2.5146)
			(layers "F.Cu" "F.Mask" "F.Paste")
			(net "P0V9_CPU0_RT3_2A")
		)
	)
	(footprint ""
		(layer "F.Cu")
		(at 468.957914 -41.105836)
		(property "Reference" "R6045"
			(at 0 0 0)
			(layer "F.SilkS")
			(hide yes)
			(effects
				(font
					(size 1.27 1.27)
				)
			)
		)
		(property "Value" ""
			(at 0 0 0)
			(layer "F.Fab")
			(effects
				(font
					(size 1.27 1.27)
				)
			)
		)
		(duplicate_pad_numbers_are_jumpers no)
		(fp_line
			(start -0.7874 -0.4064)
			(end 0.7874 -0.4064)
			(stroke
				(width 0.1524)
				(type default)
			)
			(layer "F.SilkS")
		)
		(fp_line
			(start -0.7874 0.4064)
			(end -0.7874 -0.4064)
			(stroke
				(width 0.1524)
				(type default)
			)
			(layer "F.SilkS")
		)
		(fp_line
			(start 0.7874 -0.4064)
			(end 0.7874 0.4064)
			(stroke
				(width 0.1524)
				(type default)
			)
			(layer "F.SilkS")
		)
		(fp_line
			(start 0.7874 0.4064)
			(end -0.7874 0.4064)
			(stroke
				(width 0.1524)
				(type default)
			)
			(layer "F.SilkS")
		)
		(fp_line
			(start -0.67945 -0.305054)
			(end -0.12065 -0.305054)
			(stroke
				(width 0.1)
				(type default)
			)
			(layer "F.Fab")
		)
		(fp_line
			(start -0.67945 0.3048)
			(end -0.67945 -0.305054)
			(stroke
				(width 0.1)
				(type default)
			)
			(layer "F.Fab")
		)
		(fp_line
			(start -0.12065 -0.305054)
			(end -0.12065 -0.2794)
			(stroke
				(width 0.1)
				(type default)
			)
			(layer "F.Fab")
		)
		(fp_line
			(start -0.12065 -0.2794)
			(end 0.12065 -0.2794)
			(stroke
				(width 0.1)
				(type default)
			)
			(layer "F.Fab")
		)
		(fp_line
			(start -0.12065 0.2794)
			(end -0.12065 0.3048)
			(stroke
				(width 0.1)
				(type default)
			)
			(layer "F.Fab")
		)
		(fp_line
			(start -0.12065 0.3048)
			(end -0.67945 0.3048)
			(stroke
				(width 0.1)
				(type default)
			)
			(layer "F.Fab")
		)
		(fp_line
			(start 0.120396 0.2794)
			(end -0.12065 0.2794)
			(stroke
				(width 0.1)
				(type default)
			)
			(layer "F.Fab")
		)
		(fp_line
			(start 0.120396 0.3048)
			(end 0.120396 0.2794)
			(stroke
				(width 0.1)
				(type default)
			)
			(layer "F.Fab")
		)
		(fp_line
			(start 0.12065 -0.3048)
			(end 0.67945 -0.3048)
			(stroke
				(width 0.1)
				(type default)
			)
			(layer "F.Fab")
		)
		(fp_line
			(start 0.12065 -0.2794)
			(end 0.12065 -0.3048)
			(stroke
				(width 0.1)
				(type default)
			)
			(layer "F.Fab")
		)
		(fp_line
			(start 0.67945 -0.3048)
			(end 0.67945 0.3048)
			(stroke
				(width 0.1)
				(type default)
			)
			(layer "F.Fab")
		)
		(fp_line
			(start 0.67945 0.3048)
			(end 0.120396 0.3048)
			(stroke
				(width 0.1)
				(type default)
			)
			(layer "F.Fab")
		)
		(pad "1" smd circle
			(at -0.40005 0)
			(size 0 0)
			(layers "F.Cu" "F.Mask" "F.Paste")
			(net "P12V_OCP_EN_1_R")
		)
		(pad "2" smd circle
			(at 0.40005 0)
			(size 0 0)
			(layers "F.Cu" "F.Mask" "F.Paste")
			(net "GND")
		)
	)
	(footprint ""
		(layer "F.Cu")
		(at 178.943 -140.172948 90)
		(property "Reference" "R19"
			(at 0 0 90)
			(layer "F.SilkS")
			(hide yes)
			(effects
				(font
					(size 1.27 1.27)
				)
			)
		)
		(property "Value" ""
			(at 0 0 90)
			(layer "F.Fab")
			(effects
				(font
					(size 1.27 1.27)
				)
			)
		)
		(duplicate_pad_numbers_are_jumpers no)
		(fp_line
			(start 0.7874 -0.4064)
			(end 0.7874 0.4064)
			(stroke
				(width 0.1524)
				(type default)
			)
			(layer "F.SilkS")
		)
		(fp_line
			(start -0.7874 -0.4064)
			(end 0.7874 -0.4064)
			(stroke
				(width 0.1524)
				(type default)
			)
			(layer "F.SilkS")
		)
		(fp_line
			(start 0.7874 0.4064)
			(end -0.7874 0.4064)
			(stroke
				(width 0.1524)
				(type default)
			)
			(layer "F.SilkS")
		)
		(fp_line
			(start -0.7874 0.4064)
			(end -0.7874 -0.4064)
			(stroke
				(width 0.1524)
				(type default)
			)
			(layer "F.SilkS")
		)
		(fp_line
			(start -0.12065 -0.305054)
			(end -0.12065 -0.2794)
			(stroke
				(width 0.1)
				(type default)
			)
			(layer "F.Fab")
		)
		(fp_line
			(start -0.67945 -0.305054)
			(end -0.12065 -0.305054)
			(stroke
				(width 0.1)
				(type default)
			)
			(layer "F.Fab")
		)
		(fp_line
			(start 0.67945 -0.3048)
			(end 0.67945 0.3048)
			(stroke
				(width 0.1)
				(type default)
			)
			(layer "F.Fab")
		)
		(fp_line
			(start 0.12065 -0.3048)
			(end 0.67945 -0.3048)
			(stroke
				(width 0.1)
				(type default)
			)
			(layer "F.Fab")
		)
		(fp_line
			(start 0.12065 -0.2794)
			(end 0.12065 -0.3048)
			(stroke
				(width 0.1)
				(type default)
			)
			(layer "F.Fab")
		)
		(fp_line
			(start -0.12065 -0.2794)
			(end 0.12065 -0.2794)
			(stroke
				(width 0.1)
				(type default)
			)
			(layer "F.Fab")
		)
		(fp_line
			(start 0.120396 0.2794)
			(end -0.12065 0.2794)
			(stroke
				(width 0.1)
				(type default)
			)
			(layer "F.Fab")
		)
		(fp_line
			(start -0.12065 0.2794)
			(end -0.12065 0.3048)
			(stroke
				(width 0.1)
				(type default)
			)
			(layer "F.Fab")
		)
		(fp_line
			(start 0.67945 0.3048)
			(end 0.120396 0.3048)
			(stroke
				(width 0.1)
				(type default)
			)
			(layer "F.Fab")
		)
		(fp_line
			(start 0.120396 0.3048)
			(end 0.120396 0.2794)
			(stroke
				(width 0.1)
				(type default)
			)
			(layer "F.Fab")
		)
		(fp_line
			(start -0.12065 0.3048)
			(end -0.67945 0.3048)
			(stroke
				(width 0.1)
				(type default)
			)
			(layer "F.Fab")
		)
		(fp_line
			(start -0.67945 0.3048)
			(end -0.67945 -0.305054)
			(stroke
				(width 0.1)
				(type default)
			)
			(layer "F.Fab")
		)
		(pad "1" smd circle
			(at -0.40005 0 90)
			(size 0 0)
			(layers "F.Cu" "F.Mask" "F.Paste")
			(net "RST_CPU1_PERST1_N")
		)
		(pad "2" smd circle
			(at 0.40005 0 90)
			(size 0 0)
			(layers "F.Cu" "F.Mask" "F.Paste")
			(net "GND")
		)
	)
	(footprint ""
		(layer "F.Cu")
		(at 243.74475 -50.335434)
		(property "Reference" "R1292"
			(at 0 0 0)
			(layer "F.SilkS")
			(hide yes)
			(effects
				(font
					(size 1.27 1.27)
				)
			)
		)
		(property "Value" ""
			(at 0 0 0)
			(layer "F.Fab")
			(effects
				(font
					(size 1.27 1.27)
				)
			)
		)
		(duplicate_pad_numbers_are_jumpers no)
		(fp_line
			(start -0.7874 -0.4064)
			(end 0.7874 -0.4064)
			(stroke
				(width 0.1524)
				(type default)
			)
			(layer "F.SilkS")
		)
		(fp_line
			(start -0.7874 0.4064)
			(end -0.7874 -0.4064)
			(stroke
				(width 0.1524)
				(type default)
			)
			(layer "F.SilkS")
		)
		(fp_line
			(start 0.7874 -0.4064)
			(end 0.7874 0.4064)
			(stroke
				(width 0.1524)
				(type default)
			)
			(layer "F.SilkS")
		)
		(fp_line
			(start 0.7874 0.4064)
			(end -0.7874 0.4064)
			(stroke
				(width 0.1524)
				(type default)
			)
			(layer "F.SilkS")
		)
		(fp_line
			(start -0.67945 -0.305054)
			(end -0.12065 -0.305054)
			(stroke
				(width 0.1)
				(type default)
			)
			(layer "F.Fab")
		)
		(fp_line
			(start -0.67945 0.3048)
			(end -0.67945 -0.305054)
			(stroke
				(width 0.1)
				(type default)
			)
			(layer "F.Fab")
		)
		(fp_line
			(start -0.12065 -0.305054)
			(end -0.12065 -0.2794)
			(stroke
				(width 0.1)
				(type default)
			)
			(layer "F.Fab")
		)
		(fp_line
			(start -0.12065 -0.2794)
			(end 0.12065 -0.2794)
			(stroke
				(width 0.1)
				(type default)
			)
			(layer "F.Fab")
		)
		(fp_line
			(start -0.12065 0.2794)
			(end -0.12065 0.3048)
			(stroke
				(width 0.1)
				(type default)
			)
			(layer "F.Fab")
		)
		(fp_line
			(start -0.12065 0.3048)
			(end -0.67945 0.3048)
			(stroke
				(width 0.1)
				(type default)
			)
			(layer "F.Fab")
		)
		(fp_line
			(start 0.120396 0.2794)
			(end -0.12065 0.2794)
			(stroke
				(width 0.1)
				(type default)
			)
			(layer "F.Fab")
		)
		(fp_line
			(start 0.120396 0.3048)
			(end 0.120396 0.2794)
			(stroke
				(width 0.1)
				(type default)
			)
			(layer "F.Fab")
		)
		(fp_line
			(start 0.12065 -0.3048)
			(end 0.67945 -0.3048)
			(stroke
				(width 0.1)
				(type default)
			)
			(layer "F.Fab")
		)
		(fp_line
			(start 0.12065 -0.2794)
			(end 0.12065 -0.3048)
			(stroke
				(width 0.1)
				(type default)
			)
			(layer "F.Fab")
		)
		(fp_line
			(start 0.67945 -0.3048)
			(end 0.67945 0.3048)
			(stroke
				(width 0.1)
				(type default)
			)
			(layer "F.Fab")
		)
		(fp_line
			(start 0.67945 0.3048)
			(end 0.120396 0.3048)
			(stroke
				(width 0.1)
				(type default)
			)
			(layer "F.Fab")
		)
		(pad "1" smd circle
			(at -0.40005 0)
			(size 0 0)
			(layers "F.Cu" "F.Mask" "F.Paste")
			(net "P12V_E1S_0_R")
		)
		(pad "2" smd circle
			(at 0.40005 0)
			(size 0 0)
			(layers "F.Cu" "F.Mask" "F.Paste")
			(net "VSENSE_P12V_INA230_8_INN")
		)
	)
)
